(kicad_pcb
	(version 20211014)
	(generator pcbnew)
	(general
    (thickness 1.6)
  )
	(paper "A4")
	(title_block
    (title "SA800U (Snapdragon 845) Baseboard")
    (date "2023-10-19")
    (rev "1.0.3")
    (company "Antmicro Ltd.")
    (comment 1 "www.antmicro.com")
		(comment 9 "footprints 166-173 of 589")
	)
	(layers
    (0 "F.Cu" signal)
    (1 "In1.Cu" power)
    (2 "In2.Cu" signal)
    (3 "In3.Cu" signal)
    (4 "In4.Cu" power)
    (31 "B.Cu" signal)
    (32 "B.Adhes" user "B.Adhesive")
    (33 "F.Adhes" user "F.Adhesive")
    (34 "B.Paste" user)
    (35 "F.Paste" user)
    (36 "B.SilkS" user "B.Silkscreen")
    (37 "F.SilkS" user "F.Silkscreen")
    (38 "B.Mask" user)
    (39 "F.Mask" user)
    (40 "Dwgs.User" user "User.Drawings")
    (41 "Cmts.User" user "User.Comments")
    (42 "Eco1.User" user "User.Eco1")
    (43 "Eco2.User" user "User.Eco2")
    (44 "Edge.Cuts" user)
    (45 "Margin" user)
    (46 "B.CrtYd" user "B.Courtyard")
    (47 "F.CrtYd" user "F.Courtyard")
    (48 "B.Fab" user)
    (49 "F.Fab" user)
  )
	(footprint "sa800u-baseboard-hw-footprints:L_Murata_025020_0605Metric" (layer "F.Cu")
    (tedit 61AA2C4F)
    (at 152 121.5)
    (property "Author" "Antmicro")
    (property "License" "Apache-2.0")
    (property "MPN" "NFP0QHB242HS2D")
    (property "Manufacturer" "Murata")
    (property "Sheetfile" "lcm.kicad_sch")
    (property "Sheetname" "LCM")
    (attr smd)
    (fp_text reference "L12" (at -0.99 -0.72) (layer "F.SilkS")
      (effects (font (size 0.7 0.7) (thickness 0.15)) (justify left bottom))
    )
    (fp_text value "NFP0QHB242HS2D" (at 0 1.55) (layer "F.Fab")
      (effects (font (size 0.7 0.7) (thickness 0.15)) (justify left bottom))
    )
    (fp_text user "Author: Antmicro" (at -1.027 4.605) (layer "F.Fab") hide
      (effects (font (size 0.7 0.7) (thickness 0.15)) (justify left bottom))
    )
    (fp_text user "${REFERENCE}" (at -1.027 3.406) (layer "F.Fab") hide
      (effects (font (size 0.7 0.7) (thickness 0.15)) (justify left bottom))
    )
    (fp_text user "License: Apache-2.0" (at -1.027 5.805) (layer "F.Fab") hide
      (effects (font (size 0.7 0.7) (thickness 0.15)) (justify left bottom))
    )
    (fp_line (start 0.276 -0.45) (end -0.276 -0.45) (layer "F.SilkS") (width 0.15))
    (fp_line (start -0.276 0.45) (end 0.276 0.45) (layer "F.SilkS") (width 0.15))
    (fp_circle (center -0.5 -0.5) (end -0.449 -0.5) (layer "F.SilkS") (width 0.15) (fill solid))
    (fp_rect (start -0.5 -0.6) (end 0.5 0.6) (layer "F.CrtYd") (width 0.05) (fill none))
    (fp_line (start -0.277 0.349) (end 0.275 0.349) (layer "F.Fab") (width 0.15))
    (fp_line (start 0.275 -0.351) (end -0.277 -0.351) (layer "F.Fab") (width 0.15))
    (fp_line (start 0.275 0.349) (end 0.275 -0.351) (layer "F.Fab") (width 0.15))
    (fp_line (start -0.277 -0.351) (end -0.277 0.349) (layer "F.Fab") (width 0.15))
    (pad "1" smd rect (at -0.25 -0.24) (size 0.3 0.23) (layers "F.Cu" "F.Paste" "F.Mask")
      (net 316 "/LCM/DSI_LN2_L_N") (pinfunction "1") (pintype "passive"))
    (pad "2" smd rect (at 0.248 -0.24) (size 0.3 0.23) (layers "F.Cu" "F.Paste" "F.Mask")
      (net 91 "DSI0_LN2_N") (pinfunction "2") (pintype "passive"))
    (pad "3" smd rect (at 0.248 0.239) (size 0.3 0.23) (layers "F.Cu" "F.Paste" "F.Mask")
      (net 92 "DSI0_LN2_P") (pinfunction "3") (pintype "passive"))
    (pad "4" smd rect (at -0.25 0.239) (size 0.3 0.23) (layers "F.Cu" "F.Paste" "F.Mask")
      (net 315 "/LCM/DSI_LN2_L_P") (pinfunction "4") (pintype "passive"))
  )
	(footprint "sa800u-baseboard-hw-footprints:R_0402_1005Metric" (layer "F.Cu")
    (tedit 5FD9C158)
    (at 137.2 104)
    (descr "Resistor SMD 0402")
    (tags "resistor SMD 0402")
    (property "Author" "Antmicro")
    (property "DNP" "")
    (property "License" "Apache-2.0")
    (property "MPN" "CR0402-FX-1002GLF")
    (property "Manufacturer" "Bourns")
    (property "Sheetfile" "som.kicad_sch")
    (property "Sheetname" "SoM")
    (property "Tolerance" "1%")
    (property "Val" "10k")
    (attr smd)
    (fp_text reference "R175" (at 0.81 0.36) (layer "F.SilkS")
      (effects (font (size 0.7 0.7) (thickness 0.15)) (justify left bottom))
    )
    (fp_text value "R_10k_0402" (at 0 1.4) (layer "F.Fab")
      (effects (font (size 0.7 0.7) (thickness 0.15)) (justify left bottom))
    )
    (fp_text user "Author: Antmicro" (at -0.95 4.169) (layer "F.Fab") hide
      (effects (font (size 0.7 0.7) (thickness 0.15)) (justify left bottom))
    )
    (fp_text user "License: Apache-2.0" (at -0.95 5.169) (layer "F.Fab") hide
      (effects (font (size 0.7 0.7) (thickness 0.15)) (justify left bottom))
    )
    (fp_text user "${REFERENCE}" (at -0.95 3.168) (layer "F.Fab") hide
      (effects (font (size 0.7 0.7) (thickness 0.15)) (justify left bottom))
    )
    (fp_rect (start -0.93 -0.47) (end 0.93 0.47) (layer "F.CrtYd") (width 0.05) (fill none))
    (fp_rect (start -0.5 -0.25) (end 0.5 0.25) (layer "F.Fab") (width 0.15) (fill none))
    (pad "1" smd roundrect (at -0.485 0) (size 0.59 0.64) (layers "F.Cu" "F.Paste" "F.Mask") (roundrect_rratio 0.25)
      (net 132 "VREG_S4A_1V8") (pintype "passive"))
    (pad "2" smd roundrect (at 0.485 0) (size 0.59 0.64) (layers "F.Cu" "F.Paste" "F.Mask") (roundrect_rratio 0.25)
      (net 417 "Net-(R175-Pad2)") (pintype "passive"))
  )
	(footprint "sa800u-baseboard-hw-footprints:R_0402_1005Metric" (layer "F.Cu")
    (tedit 5FD9C158)
    (at 121.9 93.8 -90)
    (descr "Resistor SMD 0402")
    (tags "resistor SMD 0402")
    (property "Author" "Antmicro")
    (property "DNP" "DNP")
    (property "License" "Apache-2.0")
    (property "MPN" "CR0402-FX-1001GLF")
    (property "Manufacturer" "Bourns")
    (property "Sheetfile" "other-interfaces.kicad_sch")
    (property "Sheetname" "Other Interfaces")
    (property "Tolerance" "1%")
    (property "Val" "1k")
    (attr exclude_from_pos_files)
    (fp_text reference "R95" (at -0.84 -0.33 -90) (layer "F.SilkS")
      (effects (font (size 0.7 0.7) (thickness 0.15)) (justify left bottom))
    )
    (fp_text value "R_1k_0402" (at 0 1.4 -90) (layer "F.Fab")
      (effects (font (size 0.7 0.7) (thickness 0.15)) (justify left bottom))
    )
    (fp_text user "Author: Antmicro" (at -0.95 4.169 -90) (layer "F.Fab") hide
      (effects (font (size 0.7 0.7) (thickness 0.15)) (justify left bottom))
    )
    (fp_text user "${REFERENCE}" (at -0.95 3.168 -90) (layer "F.Fab") hide
      (effects (font (size 0.7 0.7) (thickness 0.15)) (justify left bottom))
    )
    (fp_text user "License: Apache-2.0" (at -0.95 5.169 -90) (layer "F.Fab") hide
      (effects (font (size 0.7 0.7) (thickness 0.15)) (justify left bottom))
    )
    (fp_rect (start -0.93 -0.47) (end 0.93 0.47) (layer "F.CrtYd") (width 0.05) (fill none))
    (fp_rect (start -0.5 -0.25) (end 0.5 0.25) (layer "F.Fab") (width 0.15) (fill none))
    (pad "1" smd roundrect (at -0.485 0 270) (size 0.59 0.64) (layers "F.Cu" "F.Paste" "F.Mask") (roundrect_rratio 0.25)
      (net 112 "SD_DET") (pintype "passive"))
    (pad "2" smd roundrect (at 0.485 0 270) (size 0.59 0.64) (layers "F.Cu" "F.Paste" "F.Mask") (roundrect_rratio 0.25)
      (net 246 "/Other Interfaces/SD_DET_R") (pintype "passive"))
  )
	(footprint "sa800u-baseboard-hw-footprints:R_0402_1005Metric" (layer "F.Cu")
    (tedit 5FD9C158)
    (at 122.9 93.8 -90)
    (descr "Resistor SMD 0402")
    (tags "resistor SMD 0402")
    (property "Author" "Antmicro")
    (property "License" "Apache-2.0")
    (property "MPN" "CR0402-FX-33R0GLF")
    (property "Manufacturer" "Bourns")
    (property "Sheetfile" "other-interfaces.kicad_sch")
    (property "Sheetname" "Other Interfaces")
    (property "Tolerance" "1%")
    (property "Val" "33R")
    (attr smd)
    (fp_text reference "R98" (at -0.84 -0.33 -90) (layer "F.SilkS")
      (effects (font (size 0.7 0.7) (thickness 0.15)) (justify left bottom))
    )
    (fp_text value "R_33R_0402" (at 0 1.4 -90) (layer "F.Fab")
      (effects (font (size 0.7 0.7) (thickness 0.15)) (justify left bottom))
    )
    (fp_text user "Author: Antmicro" (at -0.95 4.169 -90) (layer "F.Fab") hide
      (effects (font (size 0.7 0.7) (thickness 0.15)) (justify left bottom))
    )
    (fp_text user "${REFERENCE}" (at -0.95 3.168 -90) (layer "F.Fab") hide
      (effects (font (size 0.7 0.7) (thickness 0.15)) (justify left bottom))
    )
    (fp_text user "License: Apache-2.0" (at -0.95 5.169 -90) (layer "F.Fab") hide
      (effects (font (size 0.7 0.7) (thickness 0.15)) (justify left bottom))
    )
    (fp_rect (start -0.93 -0.47) (end 0.93 0.47) (layer "F.CrtYd") (width 0.05) (fill none))
    (fp_rect (start -0.5 -0.25) (end 0.5 0.25) (layer "F.Fab") (width 0.15) (fill none))
    (pad "1" smd roundrect (at -0.485 0 270) (size 0.59 0.64) (layers "F.Cu" "F.Paste" "F.Mask") (roundrect_rratio 0.25)
      (net 115 "SD_CMD") (pintype "passive"))
    (pad "2" smd roundrect (at 0.485 0 270) (size 0.59 0.64) (layers "F.Cu" "F.Paste" "F.Mask") (roundrect_rratio 0.25)
      (net 248 "/Other Interfaces/SD_CMD_R") (pintype "passive"))
  )
	(footprint "sa800u-baseboard-hw-footprints:R_0402_1005Metric" (layer "F.Cu")
    (tedit 5FD9C158)
    (at 119.9 93.8 -90)
    (descr "Resistor SMD 0402")
    (tags "resistor SMD 0402")
    (property "Author" "Antmicro")
    (property "License" "Apache-2.0")
    (property "MPN" "CR0402-FX-33R0GLF")
    (property "Manufacturer" "Bourns")
    (property "Sheetfile" "other-interfaces.kicad_sch")
    (property "Sheetname" "Other Interfaces")
    (property "Tolerance" "1%")
    (property "Val" "33R")
    (attr smd)
    (fp_text reference "R96" (at -0.84 -0.33 -90) (layer "F.SilkS")
      (effects (font (size 0.7 0.7) (thickness 0.15)) (justify left bottom))
    )
    (fp_text value "R_33R_0402" (at 0 1.4 -90) (layer "F.Fab")
      (effects (font (size 0.7 0.7) (thickness 0.15)) (justify left bottom))
    )
    (fp_text user "Author: Antmicro" (at -0.95 4.169 -90) (layer "F.Fab") hide
      (effects (font (size 0.7 0.7) (thickness 0.15)) (justify left bottom))
    )
    (fp_text user "License: Apache-2.0" (at -0.95 5.169 -90) (layer "F.Fab") hide
      (effects (font (size 0.7 0.7) (thickness 0.15)) (justify left bottom))
    )
    (fp_text user "${REFERENCE}" (at -0.95 3.168 -90) (layer "F.Fab") hide
      (effects (font (size 0.7 0.7) (thickness 0.15)) (justify left bottom))
    )
    (fp_rect (start -0.93 -0.47) (end 0.93 0.47) (layer "F.CrtYd") (width 0.05) (fill none))
    (fp_rect (start -0.5 -0.25) (end 0.5 0.25) (layer "F.Fab") (width 0.15) (fill none))
    (pad "1" smd roundrect (at -0.485 0 270) (size 0.59 0.64) (layers "F.Cu" "F.Paste" "F.Mask") (roundrect_rratio 0.25)
      (net 114 "SD_DATA2") (pintype "passive"))
    (pad "2" smd roundrect (at 0.485 0 270) (size 0.59 0.64) (layers "F.Cu" "F.Paste" "F.Mask") (roundrect_rratio 0.25)
      (net 247 "/Other Interfaces/SD_DATA2_R") (pintype "passive"))
  )
	(footprint "sa800u-baseboard-hw-footprints:R_0402_1005Metric" (layer "F.Cu")
    (tedit 5FD9C158)
    (at 120.9 93.8 -90)
    (descr "Resistor SMD 0402")
    (tags "resistor SMD 0402")
    (property "Author" "Antmicro")
    (property "License" "Apache-2.0")
    (property "MPN" "CR0402-FX-33R0GLF")
    (property "Manufacturer" "Bourns")
    (property "Sheetfile" "other-interfaces.kicad_sch")
    (property "Sheetname" "Other Interfaces")
    (property "Tolerance" "1%")
    (property "Val" "33R")
    (attr smd)
    (fp_text reference "R97" (at -0.84 -0.33 -90) (layer "F.SilkS")
      (effects (font (size 0.7 0.7) (thickness 0.15)) (justify left bottom))
    )
    (fp_text value "R_33R_0402" (at 0 1.4 -90) (layer "F.Fab")
      (effects (font (size 0.7 0.7) (thickness 0.15)) (justify left bottom))
    )
    (fp_text user "License: Apache-2.0" (at -0.95 5.169 -90) (layer "F.Fab") hide
      (effects (font (size 0.7 0.7) (thickness 0.15)) (justify left bottom))
    )
    (fp_text user "${REFERENCE}" (at -0.95 3.168 -90) (layer "F.Fab") hide
      (effects (font (size 0.7 0.7) (thickness 0.15)) (justify left bottom))
    )
    (fp_text user "Author: Antmicro" (at -0.95 4.169 -90) (layer "F.Fab") hide
      (effects (font (size 0.7 0.7) (thickness 0.15)) (justify left bottom))
    )
    (fp_rect (start -0.93 -0.47) (end 0.93 0.47) (layer "F.CrtYd") (width 0.05) (fill none))
    (fp_rect (start -0.5 -0.25) (end 0.5 0.25) (layer "F.Fab") (width 0.15) (fill none))
    (pad "1" smd roundrect (at -0.485 0 270) (size 0.59 0.64) (layers "F.Cu" "F.Paste" "F.Mask") (roundrect_rratio 0.25)
      (net 113 "SD_DATA3") (pintype "passive"))
    (pad "2" smd roundrect (at 0.485 0 270) (size 0.59 0.64) (layers "F.Cu" "F.Paste" "F.Mask") (roundrect_rratio 0.25)
      (net 249 "/Other Interfaces/SD_DATA3_R") (pintype "passive"))
  )
	(footprint "sa800u-baseboard-hw-footprints:LED_0603_1608Metric_G" (layer "F.Cu")
    (tedit 60C2DD7B)
    (at 153.2 138.16 180)
    (descr "LED SMD 0603 Green")
    (tags "LED SMD 0603 Green")
    (property "Author" "Antmicro")
    (property "License" "Apache-2.0")
    (property "MPN" "KP-1608ZGC")
    (property "Manufacturer" "Kingbright")
    (property "Sheetfile" "som.kicad_sch")
    (property "Sheetname" "SoM")
    (attr smd)
    (fp_text reference "D14" (at 1.08 -1.25 180) (layer "F.SilkS")
      (effects (font (size 0.7 0.7) (thickness 0.15)) (justify left bottom))
    )
    (fp_text value "KP-1608EC" (at 0 1.6 180) (layer "F.Fab")
      (effects (font (size 0.7 0.7) (thickness 0.15)) (justify left bottom))
    )
    (fp_text user "License: Apache-2.0" (at -1.31 5.769 180) (layer "F.Fab") hide
      (effects (font (size 0.7 0.7) (thickness 0.15)) (justify left bottom))
    )
    (fp_text user "${REFERENCE}" (at -1.31 3.769 180) (layer "F.Fab") hide
      (effects (font (size 0.7 0.7) (thickness 0.15)) (justify left bottom))
    )
    (fp_text user "Author: Antmicro" (at -1.31 4.769 180) (layer "F.Fab") hide
      (effects (font (size 0.7 0.7) (thickness 0.15)) (justify left bottom))
    )
    (fp_line (start 0.093672 -0.000008) (end -0.106328 0.199992) (layer "F.SilkS") (width 0.1))
    (fp_line (start -0.106328 -0.000008) (end -0.29 0) (layer "F.SilkS") (width 0.1))
    (fp_line (start -0.106328 -0.200008) (end -0.106328 0.199992) (layer "F.SilkS") (width 0.1))
    (fp_line (start -0.106328 -0.200008) (end 0.093672 -0.000008) (layer "F.SilkS") (width 0.1))
    (fp_line (start 0.093672 -0.200008) (end 0.093672 0.199992) (layer "F.SilkS") (width 0.1))
    (fp_line (start -0.27 -0.35) (end 0.27 -0.35) (layer "F.SilkS") (width 0.15))
    (fp_line (start 0.093672 -0.000008) (end 0.293672 -0.000008) (layer "F.SilkS") (width 0.1))
    (fp_line (start 1.25 0.32) (end 1.25 -0.32) (layer "F.SilkS") (width 0.15))
    (fp_line (start -0.27 0.351) (end 0.27 0.351) (layer "F.SilkS") (width 0.15))
    (fp_rect (start 1.26 0.65) (end -1.26 -0.65) (layer "F.CrtYd") (width 0.05) (fill none))
    (fp_line (start 0.199 0) (end 0.597 0) (layer "F.Fab") (width 0.15))
    (fp_line (start 0.101 0) (end -0.201 -0.2) (layer "F.Fab") (width 0.15))
    (fp_line (start -0.201 -0.2) (end -0.201 0) (layer "F.Fab") (width 0.15))
    (fp_line (start -0.201 0) (end -0.201 0.202) (layer "F.Fab") (width 0.15))
    (fp_line (start 0.199 0.202) (end 0.199 -0.1) (layer "F.Fab") (width 0.15))
    (fp_line (start -0.599 0) (end -0.201 0) (layer "F.Fab") (width 0.15))
    (fp_line (start 0.199 -0.2) (end 0.199 -0.1) (layer "F.Fab") (width 0.15))
    (fp_line (start -0.201 0.202) (end 0.101 0) (layer "F.Fab") (width 0.15))
    (fp_rect (start -0.848 -0.4) (end 0.85 0.402) (layer "F.Fab") (width 0.15) (fill none))
    (pad "1" smd rect (at -0.75 0) (size 0.8 0.8) (layers "F.Cu" "F.Paste" "F.Mask")
      (net 133 "5V_SYS") (pinfunction "1") (pintype "passive"))
    (pad "2" smd rect (at 0.75 0) (size 0.8 0.8) (layers "F.Cu" "F.Paste" "F.Mask")
      (net 371 "Net-(D14-Pad2)") (pinfunction "2") (pintype "passive"))
  )
	(footprint "sa800u-baseboard-hw-footprints:LED_0603_1608Metric_G" (layer "F.Cu")
    (tedit 60C2DD7B)
    (at 153.2 142 180)
    (descr "LED SMD 0603 Green")
    (tags "LED SMD 0603 Green")
    (property "Author" "Antmicro")
    (property "License" "Apache-2.0")
    (property "MPN" "KP-1608ZGC")
    (property "Manufacturer" "Kingbright")
    (property "Sheetfile" "som.kicad_sch")
    (property "Sheetname" "SoM")
    (attr smd)
    (fp_text reference "D15" (at 1.08 -1.26 180) (layer "F.SilkS")
      (effects (font (size 0.7 0.7) (thickness 0.15)) (justify left bottom))
    )
    (fp_text value "KP-1608EC" (at 0 1.6 180) (layer "F.Fab")
      (effects (font (size 0.7 0.7) (thickness 0.15)) (justify left bottom))
    )
    (fp_text user "Author: Antmicro" (at -1.31 4.769 180) (layer "F.Fab") hide
      (effects (font (size 0.7 0.7) (thickness 0.15)) (justify left bottom))
    )
    (fp_text user "${REFERENCE}" (at -1.31 3.769 180) (layer "F.Fab") hide
      (effects (font (size 0.7 0.7) (thickness 0.15)) (justify left bottom))
    )
    (fp_text user "License: Apache-2.0" (at -1.31 5.769 180) (layer "F.Fab") hide
      (effects (font (size 0.7 0.7) (thickness 0.15)) (justify left bottom))
    )
    (fp_line (start 1.25 0.32) (end 1.25 -0.32) (layer "F.SilkS") (width 0.15))
    (fp_line (start -0.106328 -0.200008) (end -0.106328 0.199992) (layer "F.SilkS") (width 0.1))
    (fp_line (start -0.106328 -0.000008) (end -0.29 0) (layer "F.SilkS") (width 0.1))
    (fp_line (start 0.093672 -0.000008) (end -0.106328 0.199992) (layer "F.SilkS") (width 0.1))
    (fp_line (start -0.27 -0.35) (end 0.27 -0.35) (layer "F.SilkS") (width 0.15))
    (fp_line (start -0.106328 -0.200008) (end 0.093672 -0.000008) (layer "F.SilkS") (width 0.1))
    (fp_line (start 0.093672 -0.000008) (end 0.293672 -0.000008) (layer "F.SilkS") (width 0.1))
    (fp_line (start 0.093672 -0.200008) (end 0.093672 0.199992) (layer "F.SilkS") (width 0.1))
    (fp_line (start -0.27 0.351) (end 0.27 0.351) (layer "F.SilkS") (width 0.15))
    (fp_rect (start 1.26 0.65) (end -1.26 -0.65) (layer "F.CrtYd") (width 0.05) (fill none))
    (fp_line (start 0.199 0.202) (end 0.199 -0.1) (layer "F.Fab") (width 0.15))
    (fp_line (start 0.199 0) (end 0.597 0) (layer "F.Fab") (width 0.15))
    (fp_line (start -0.201 0.202) (end 0.101 0) (layer "F.Fab") (width 0.15))
    (fp_line (start 0.101 0) (end -0.201 -0.2) (layer "F.Fab") (width 0.15))
    (fp_line (start -0.201 -0.2) (end -0.201 0) (layer "F.Fab") (width 0.15))
    (fp_line (start -0.201 0) (end -0.201 0.202) (layer "F.Fab") (width 0.15))
    (fp_line (start 0.199 -0.2) (end 0.199 -0.1) (layer "F.Fab") (width 0.15))
    (fp_line (start -0.599 0) (end -0.201 0) (layer "F.Fab") (width 0.15))
    (fp_rect (start -0.848 -0.4) (end 0.85 0.402) (layer "F.Fab") (width 0.15) (fill none))
    (pad "1" smd rect (at -0.75 0) (size 0.8 0.8) (layers "F.Cu" "F.Paste" "F.Mask")
      (net 133 "5V_SYS") (pinfunction "1") (pintype "passive"))
    (pad "2" smd rect (at 0.75 0) (size 0.8 0.8) (layers "F.Cu" "F.Paste" "F.Mask")
      (net 372 "Net-(D15-Pad2)") (pinfunction "2") (pintype "passive"))
  )
)
